(kicad_pcb
	(version 20260206)
	(generator "pcbnew")
	(generator_version "10.0")
	(general
		(thickness 1.6)
		(legacy_teardrops no)
	)
	(paper "A4")
	(title_block
		(title "01162023_DA0F0TEBIF0_F0T_Expander_BD_F_brd_V02_OCP.brd")
		(comment 1 "Grand Teton / footprints 5036-5042 of 9728")
	)
	(layers
		(0 "F.Cu" signal "TOP")
		(4 "In1.Cu" signal "GND")
		(6 "In2.Cu" signal "VCC")
		(8 "In3.Cu" signal "VCC1")
		(10 "In4.Cu" signal "GND1")
		(12 "In5.Cu" signal "IN1")
		(14 "In6.Cu" signal "GND2")
		(16 "In7.Cu" signal "IN2")
		(18 "In8.Cu" signal "GND3")
		(20 "In9.Cu" signal "IN3")
		(22 "In10.Cu" signal "GND4")
		(24 "In11.Cu" signal "IN4")
		(26 "In12.Cu" signal "GND5")
		(28 "In13.Cu" signal "IN5")
		(30 "In14.Cu" signal "GND6")
		(32 "In15.Cu" signal "IN6")
		(34 "In16.Cu" signal "GND7")
		(2 "B.Cu" signal "BOTTOM")
		(9 "F.Adhes" user "F.Adhesive")
		(11 "B.Adhes" user "B.Adhesive")
		(13 "F.Paste" user "Package Geometry/Pastemask Top")
		(15 "B.Paste" user "Package Geometry/Pastemask Bottom")
		(5 "F.SilkS" user "Ref Des/Silkscreen Top")
		(7 "B.SilkS" user "Ref Des/Silkscreen Bottom")
		(1 "F.Mask" user "Board Geometry/Soldermask Top")
		(3 "B.Mask" user "Board Geometry/Soldermask Bottom")
		(17 "Dwgs.User" user "User.Drawings")
		(19 "Cmts.User" user "User.Comments")
		(21 "Eco1.User" user "User.Eco1")
		(23 "Eco2.User" user "User.Eco2")
		(25 "Edge.Cuts" user "Board Geometry/Outline")
		(27 "Margin" user)
		(31 "F.CrtYd" user "Package Geometry/Place Bound Top")
		(29 "B.CrtYd" user "Package Geometry/Place Bound Bottom")
		(35 "F.Fab" user "Ref Des/Assembly Top")
		(33 "B.Fab" user "Ref Des/Assembly Bottom")
	)
	(footprint ""
		(layer "F.Cu")
		(at 55.9816 -158.8516)
		(property "Reference" "R47"
			(at 0 0 0)
			(layer "F.SilkS")
			(hide yes)
			(effects
				(font
					(size 1.27 1.27)
				)
			)
		)
		(property "Value" ""
			(at 0 0 0)
			(layer "F.Fab")
			(effects
				(font
					(size 1.27 1.27)
				)
			)
		)
		(duplicate_pad_numbers_are_jumpers no)
		(fp_line
			(start -0.7874 -0.4064)
			(end 0.7874 -0.4064)
			(stroke
				(width 0.1524)
				(type default)
			)
			(layer "F.SilkS")
		)
		(fp_line
			(start -0.7874 0.4064)
			(end -0.7874 -0.4064)
			(stroke
				(width 0.1524)
				(type default)
			)
			(layer "F.SilkS")
		)
		(fp_line
			(start 0.7874 -0.4064)
			(end 0.7874 0.4064)
			(stroke
				(width 0.1524)
				(type default)
			)
			(layer "F.SilkS")
		)
		(fp_line
			(start 0.7874 0.4064)
			(end -0.7874 0.4064)
			(stroke
				(width 0.1524)
				(type default)
			)
			(layer "F.SilkS")
		)
		(fp_line
			(start -0.67945 -0.305054)
			(end -0.12065 -0.305054)
			(stroke
				(width 0.1)
				(type default)
			)
			(layer "F.Fab")
		)
		(fp_line
			(start -0.67945 0.3048)
			(end -0.67945 -0.305054)
			(stroke
				(width 0.1)
				(type default)
			)
			(layer "F.Fab")
		)
		(fp_line
			(start -0.12065 -0.305054)
			(end -0.12065 -0.2794)
			(stroke
				(width 0.1)
				(type default)
			)
			(layer "F.Fab")
		)
		(fp_line
			(start -0.12065 -0.2794)
			(end 0.12065 -0.2794)
			(stroke
				(width 0.1)
				(type default)
			)
			(layer "F.Fab")
		)
		(fp_line
			(start -0.12065 0.2794)
			(end -0.12065 0.3048)
			(stroke
				(width 0.1)
				(type default)
			)
			(layer "F.Fab")
		)
		(fp_line
			(start -0.12065 0.3048)
			(end -0.67945 0.3048)
			(stroke
				(width 0.1)
				(type default)
			)
			(layer "F.Fab")
		)
		(fp_line
			(start 0.120396 0.2794)
			(end -0.12065 0.2794)
			(stroke
				(width 0.1)
				(type default)
			)
			(layer "F.Fab")
		)
		(fp_line
			(start 0.120396 0.3048)
			(end 0.120396 0.2794)
			(stroke
				(width 0.1)
				(type default)
			)
			(layer "F.Fab")
		)
		(fp_line
			(start 0.12065 -0.3048)
			(end 0.67945 -0.3048)
			(stroke
				(width 0.1)
				(type default)
			)
			(layer "F.Fab")
		)
		(fp_line
			(start 0.12065 -0.2794)
			(end 0.12065 -0.3048)
			(stroke
				(width 0.1)
				(type default)
			)
			(layer "F.Fab")
		)
		(fp_line
			(start 0.67945 -0.3048)
			(end 0.67945 0.3048)
			(stroke
				(width 0.1)
				(type default)
			)
			(layer "F.Fab")
		)
		(fp_line
			(start 0.67945 0.3048)
			(end 0.120396 0.3048)
			(stroke
				(width 0.1)
				(type default)
			)
			(layer "F.Fab")
		)
		(pad "1" smd circle
			(at -0.40005 0)
			(size 0 0)
			(layers "F.Cu" "F.Mask" "F.Paste")
			(net "RST_NIC0_PERST2_R_N")
		)
		(pad "2" smd circle
			(at 0.40005 0)
			(size 0 0)
			(layers "F.Cu" "F.Mask" "F.Paste")
			(net "RST_HP_NIC0_BUF_N")
		)
	)
	(footprint ""
		(layer "F.Cu")
		(at 312.21934 -134.394702 180)
		(property "Reference" "C441"
			(at 0 0 180)
			(layer "F.SilkS")
			(hide yes)
			(effects
				(font
					(size 1.27 1.27)
				)
			)
		)
		(property "Value" ""
			(at 0 0 180)
			(layer "F.Fab")
			(effects
				(font
					(size 1.27 1.27)
				)
			)
		)
		(duplicate_pad_numbers_are_jumpers no)
		(fp_line
			(start 0.299974 0.150114)
			(end -0.299974 0.150114)
			(stroke
				(width 0.1)
				(type default)
			)
			(layer "F.Fab")
		)
		(fp_line
			(start 0.299974 -0.150114)
			(end 0.299974 0.150114)
			(stroke
				(width 0.1)
				(type default)
			)
			(layer "F.Fab")
		)
		(fp_line
			(start -0.299974 0.150114)
			(end -0.299974 -0.150114)
			(stroke
				(width 0.1)
				(type default)
			)
			(layer "F.Fab")
		)
		(fp_line
			(start -0.299974 -0.150114)
			(end 0.299974 -0.150114)
			(stroke
				(width 0.1)
				(type default)
			)
			(layer "F.Fab")
		)
		(pad "1" smd rect
			(at -0.2667 0 180)
			(size 0.3048 0.381)
			(layers "F.Cu" "F.Mask" "F.Paste")
			(net "P5E_PEX2_STN0_TX_DP<6>")
		)
		(pad "2" smd rect
			(at 0.2667 0 180)
			(size 0.3048 0.381)
			(layers "F.Cu" "F.Mask" "F.Paste")
			(net "P5E_PEX2_STN0_TX_C_DP<6>")
		)
	)
	(footprint ""
		(layer "F.Cu")
		(at 1.599692 -24.934164 -90)
		(property "Reference" "R1632"
			(at 0 0 270)
			(layer "F.SilkS")
			(hide yes)
			(effects
				(font
					(size 1.27 1.27)
				)
			)
		)
		(property "Value" ""
			(at 0 0 270)
			(layer "F.Fab")
			(effects
				(font
					(size 1.27 1.27)
				)
			)
		)
		(duplicate_pad_numbers_are_jumpers no)
		(fp_line
			(start -0.7874 0.4064)
			(end -0.7874 -0.4064)
			(stroke
				(width 0.1524)
				(type default)
			)
			(layer "F.SilkS")
		)
		(fp_line
			(start 0.7874 0.4064)
			(end -0.7874 0.4064)
			(stroke
				(width 0.1524)
				(type default)
			)
			(layer "F.SilkS")
		)
		(fp_line
			(start -0.7874 -0.4064)
			(end 0.7874 -0.4064)
			(stroke
				(width 0.1524)
				(type default)
			)
			(layer "F.SilkS")
		)
		(fp_line
			(start 0.7874 -0.4064)
			(end 0.7874 0.4064)
			(stroke
				(width 0.1524)
				(type default)
			)
			(layer "F.SilkS")
		)
		(fp_line
			(start -0.67945 0.3048)
			(end -0.67945 -0.305054)
			(stroke
				(width 0.1)
				(type default)
			)
			(layer "F.Fab")
		)
		(fp_line
			(start -0.12065 0.3048)
			(end -0.67945 0.3048)
			(stroke
				(width 0.1)
				(type default)
			)
			(layer "F.Fab")
		)
		(fp_line
			(start 0.120396 0.3048)
			(end 0.120396 0.2794)
			(stroke
				(width 0.1)
				(type default)
			)
			(layer "F.Fab")
		)
		(fp_line
			(start 0.67945 0.3048)
			(end 0.120396 0.3048)
			(stroke
				(width 0.1)
				(type default)
			)
			(layer "F.Fab")
		)
		(fp_line
			(start -0.12065 0.2794)
			(end -0.12065 0.3048)
			(stroke
				(width 0.1)
				(type default)
			)
			(layer "F.Fab")
		)
		(fp_line
			(start 0.120396 0.2794)
			(end -0.12065 0.2794)
			(stroke
				(width 0.1)
				(type default)
			)
			(layer "F.Fab")
		)
		(fp_line
			(start -0.12065 -0.2794)
			(end 0.12065 -0.2794)
			(stroke
				(width 0.1)
				(type default)
			)
			(layer "F.Fab")
		)
		(fp_line
			(start 0.12065 -0.2794)
			(end 0.12065 -0.3048)
			(stroke
				(width 0.1)
				(type default)
			)
			(layer "F.Fab")
		)
		(fp_line
			(start 0.12065 -0.3048)
			(end 0.67945 -0.3048)
			(stroke
				(width 0.1)
				(type default)
			)
			(layer "F.Fab")
		)
		(fp_line
			(start 0.67945 -0.3048)
			(end 0.67945 0.3048)
			(stroke
				(width 0.1)
				(type default)
			)
			(layer "F.Fab")
		)
		(fp_line
			(start -0.67945 -0.305054)
			(end -0.12065 -0.305054)
			(stroke
				(width 0.1)
				(type default)
			)
			(layer "F.Fab")
		)
		(fp_line
			(start -0.12065 -0.305054)
			(end -0.12065 -0.2794)
			(stroke
				(width 0.1)
				(type default)
			)
			(layer "F.Fab")
		)
		(pad "1" smd circle
			(at -0.40005 0 270)
			(size 0 0)
			(layers "F.Cu" "F.Mask" "F.Paste")
			(net "P3V3_SSD0")
		)
		(pad "2" smd circle
			(at 0.40005 0 270)
			(size 0 0)
			(layers "F.Cu" "F.Mask" "F.Paste")
			(net "SMB_ISO_SSD0_SCL")
		)
	)
	(footprint ""
		(layer "F.Cu")
		(at 21.872956 -172.239178)
		(property "Reference" "PR57"
			(at 0 0 0)
			(layer "F.SilkS")
			(hide yes)
			(effects
				(font
					(size 1.27 1.27)
				)
			)
		)
		(property "Value" ""
			(at 0 0 0)
			(layer "F.Fab")
			(effects
				(font
					(size 1.27 1.27)
				)
			)
		)
		(duplicate_pad_numbers_are_jumpers no)
		(fp_line
			(start -0.7874 -0.4064)
			(end 0.7874 -0.4064)
			(stroke
				(width 0.1524)
				(type default)
			)
			(layer "F.SilkS")
		)
		(fp_line
			(start -0.7874 0.4064)
			(end -0.7874 -0.4064)
			(stroke
				(width 0.1524)
				(type default)
			)
			(layer "F.SilkS")
		)
		(fp_line
			(start 0.7874 -0.4064)
			(end 0.7874 0.4064)
			(stroke
				(width 0.1524)
				(type default)
			)
			(layer "F.SilkS")
		)
		(fp_line
			(start 0.7874 0.4064)
			(end -0.7874 0.4064)
			(stroke
				(width 0.1524)
				(type default)
			)
			(layer "F.SilkS")
		)
		(fp_line
			(start -0.67945 -0.305054)
			(end -0.12065 -0.305054)
			(stroke
				(width 0.1)
				(type default)
			)
			(layer "F.Fab")
		)
		(fp_line
			(start -0.67945 0.3048)
			(end -0.67945 -0.305054)
			(stroke
				(width 0.1)
				(type default)
			)
			(layer "F.Fab")
		)
		(fp_line
			(start -0.12065 -0.305054)
			(end -0.12065 -0.2794)
			(stroke
				(width 0.1)
				(type default)
			)
			(layer "F.Fab")
		)
		(fp_line
			(start -0.12065 -0.2794)
			(end 0.12065 -0.2794)
			(stroke
				(width 0.1)
				(type default)
			)
			(layer "F.Fab")
		)
		(fp_line
			(start -0.12065 0.2794)
			(end -0.12065 0.3048)
			(stroke
				(width 0.1)
				(type default)
			)
			(layer "F.Fab")
		)
		(fp_line
			(start -0.12065 0.3048)
			(end -0.67945 0.3048)
			(stroke
				(width 0.1)
				(type default)
			)
			(layer "F.Fab")
		)
		(fp_line
			(start 0.120396 0.2794)
			(end -0.12065 0.2794)
			(stroke
				(width 0.1)
				(type default)
			)
			(layer "F.Fab")
		)
		(fp_line
			(start 0.120396 0.3048)
			(end 0.120396 0.2794)
			(stroke
				(width 0.1)
				(type default)
			)
			(layer "F.Fab")
		)
		(fp_line
			(start 0.12065 -0.3048)
			(end 0.67945 -0.3048)
			(stroke
				(width 0.1)
				(type default)
			)
			(layer "F.Fab")
		)
		(fp_line
			(start 0.12065 -0.2794)
			(end 0.12065 -0.3048)
			(stroke
				(width 0.1)
				(type default)
			)
			(layer "F.Fab")
		)
		(fp_line
			(start 0.67945 -0.3048)
			(end 0.67945 0.3048)
			(stroke
				(width 0.1)
				(type default)
			)
			(layer "F.Fab")
		)
		(fp_line
			(start 0.67945 0.3048)
			(end 0.120396 0.3048)
			(stroke
				(width 0.1)
				(type default)
			)
			(layer "F.Fab")
		)
		(pad "1" smd circle
			(at -0.40005 0)
			(size 0 0)
			(layers "F.Cu" "F.Mask" "F.Paste")
			(net "P5V_AUX_FB")
		)
		(pad "2" smd circle
			(at 0.40005 0)
			(size 0 0)
			(layers "F.Cu" "F.Mask" "F.Paste")
			(net "SH_P5V_AUX_FB")
		)
	)
	(footprint ""
		(layer "F.Cu")
		(at 438.164732 -343.952322 90)
		(property "Reference" "C2466"
			(at 0 0 90)
			(layer "F.SilkS")
			(hide yes)
			(effects
				(font
					(size 1.27 1.27)
				)
			)
		)
		(property "Value" ""
			(at 0 0 90)
			(layer "F.Fab")
			(effects
				(font
					(size 1.27 1.27)
				)
			)
		)
		(duplicate_pad_numbers_are_jumpers no)
		(fp_line
			(start 0.299974 -0.150114)
			(end 0.299974 0.150114)
			(stroke
				(width 0.1)
				(type default)
			)
			(layer "F.Fab")
		)
		(fp_line
			(start -0.299974 -0.150114)
			(end 0.299974 -0.150114)
			(stroke
				(width 0.1)
				(type default)
			)
			(layer "F.Fab")
		)
		(fp_line
			(start 0.299974 0.150114)
			(end -0.299974 0.150114)
			(stroke
				(width 0.1)
				(type default)
			)
			(layer "F.Fab")
		)
		(fp_line
			(start -0.299974 0.150114)
			(end -0.299974 -0.150114)
			(stroke
				(width 0.1)
				(type default)
			)
			(layer "F.Fab")
		)
		(pad "1" smd rect
			(at -0.2667 0 90)
			(size 0.3048 0.381)
			(layers "F.Cu" "F.Mask" "F.Paste")
			(net "P5E_PEX3_STN4_TX_DN<66>")
		)
		(pad "2" smd rect
			(at 0.2667 0 90)
			(size 0.3048 0.381)
			(layers "F.Cu" "F.Mask" "F.Paste")
			(net "P5E_PEX3_STN4_TX_C_DN<66>")
		)
	)
	(footprint ""
		(layer "F.Cu")
		(at 347.091 -234.061 -90)
		(property "Reference" "R3568"
			(at 0 0 270)
			(layer "F.SilkS")
			(hide yes)
			(effects
				(font
					(size 1.27 1.27)
				)
			)
		)
		(property "Value" ""
			(at 0 0 270)
			(layer "F.Fab")
			(effects
				(font
					(size 1.27 1.27)
				)
			)
		)
		(duplicate_pad_numbers_are_jumpers no)
		(fp_line
			(start -0.7874 0.4064)
			(end -0.7874 -0.4064)
			(stroke
				(width 0.1524)
				(type default)
			)
			(layer "F.SilkS")
		)
		(fp_line
			(start 0.7874 0.4064)
			(end -0.7874 0.4064)
			(stroke
				(width 0.1524)
				(type default)
			)
			(layer "F.SilkS")
		)
		(fp_line
			(start -0.7874 -0.4064)
			(end 0.7874 -0.4064)
			(stroke
				(width 0.1524)
				(type default)
			)
			(layer "F.SilkS")
		)
		(fp_line
			(start 0.7874 -0.4064)
			(end 0.7874 0.4064)
			(stroke
				(width 0.1524)
				(type default)
			)
			(layer "F.SilkS")
		)
		(fp_line
			(start -0.67945 0.3048)
			(end -0.67945 -0.305054)
			(stroke
				(width 0.1)
				(type default)
			)
			(layer "F.Fab")
		)
		(fp_line
			(start -0.12065 0.3048)
			(end -0.67945 0.3048)
			(stroke
				(width 0.1)
				(type default)
			)
			(layer "F.Fab")
		)
		(fp_line
			(start 0.120396 0.3048)
			(end 0.120396 0.2794)
			(stroke
				(width 0.1)
				(type default)
			)
			(layer "F.Fab")
		)
		(fp_line
			(start 0.67945 0.3048)
			(end 0.120396 0.3048)
			(stroke
				(width 0.1)
				(type default)
			)
			(layer "F.Fab")
		)
		(fp_line
			(start -0.12065 0.2794)
			(end -0.12065 0.3048)
			(stroke
				(width 0.1)
				(type default)
			)
			(layer "F.Fab")
		)
		(fp_line
			(start 0.120396 0.2794)
			(end -0.12065 0.2794)
			(stroke
				(width 0.1)
				(type default)
			)
			(layer "F.Fab")
		)
		(fp_line
			(start -0.12065 -0.2794)
			(end 0.12065 -0.2794)
			(stroke
				(width 0.1)
				(type default)
			)
			(layer "F.Fab")
		)
		(fp_line
			(start 0.12065 -0.2794)
			(end 0.12065 -0.3048)
			(stroke
				(width 0.1)
				(type default)
			)
			(layer "F.Fab")
		)
		(fp_line
			(start 0.12065 -0.3048)
			(end 0.67945 -0.3048)
			(stroke
				(width 0.1)
				(type default)
			)
			(layer "F.Fab")
		)
		(fp_line
			(start 0.67945 -0.3048)
			(end 0.67945 0.3048)
			(stroke
				(width 0.1)
				(type default)
			)
			(layer "F.Fab")
		)
		(fp_line
			(start -0.67945 -0.305054)
			(end -0.12065 -0.305054)
			(stroke
				(width 0.1)
				(type default)
			)
			(layer "F.Fab")
		)
		(fp_line
			(start -0.12065 -0.305054)
			(end -0.12065 -0.2794)
			(stroke
				(width 0.1)
				(type default)
			)
			(layer "F.Fab")
		)
		(pad "1" smd circle
			(at -0.40005 0 270)
			(size 0 0)
			(layers "F.Cu" "F.Mask" "F.Paste")
			(net "RST_SSD5_PERST_R_N")
		)
		(pad "2" smd circle
			(at 0.40005 0 270)
			(size 0 0)
			(layers "F.Cu" "F.Mask" "F.Paste")
			(net "RST_SSD5_PERST_N")
		)
	)
	(footprint ""
		(layer "F.Cu")
		(at 183.242712 -70.844918 -90)
		(property "Reference" "PD106"
			(at 3.941318 2.088642 90)
			(unlocked yes)
			(layer "F.SilkS")
			(effects
				(font
					(size 0.7874 0.5842)
					(thickness 0.1524)
				)
				(justify left)
			)
		)
		(property "Value" ""
			(at 0 0 270)
			(layer "F.Fab")
			(effects
				(font
					(size 1.27 1.27)
				)
			)
		)
		(duplicate_pad_numbers_are_jumpers no)
		(fp_line
			(start -3.400044 1.459992)
			(end -3.400044 -1.459992)
			(stroke
				(width 0.1524)
				(type default)
			)
			(layer "F.SilkS")
		)
		(fp_line
			(start 4.107942 1.459992)
			(end -3.400044 1.459992)
			(stroke
				(width 0.1524)
				(type default)
			)
			(layer "F.SilkS")
		)
		(fp_line
			(start -3.400044 -1.459992)
			(end 4.107942 -1.459992)
			(stroke
				(width 0.1524)
				(type default)
			)
			(layer "F.SilkS")
		)
		(fp_line
			(start 4.107942 -1.459992)
			(end 4.107942 1.459992)
			(stroke
				(width 0.1524)
				(type default)
			)
			(layer "F.SilkS")
		)
		(fp_poly
			(pts
				(xy 4.107942 -1.459992) (xy 4.107942 1.459992) (xy 3.308096 1.459992) (xy 3.308096 -1.459992)
			)
			(stroke
				(width 0)
				(type default)
			)
			(fill yes)
			(layer "F.SilkS")
		)
		(fp_line
			(start -2.29997 1.459992)
			(end -2.29997 -1.459992)
			(stroke
				(width 0.1)
				(type default)
			)
			(layer "F.Fab")
		)
		(fp_line
			(start 2.29997 1.459992)
			(end -2.29997 1.459992)
			(stroke
				(width 0.1)
				(type default)
			)
			(layer "F.Fab")
		)
		(fp_line
			(start -2.29997 -1.459992)
			(end 2.29997 -1.459992)
			(stroke
				(width 0.1)
				(type default)
			)
			(layer "F.Fab")
		)
		(fp_line
			(start 2.29997 -1.459992)
			(end 2.29997 1.459992)
			(stroke
				(width 0.1)
				(type default)
			)
			(layer "F.Fab")
		)
		(fp_text user "-"
			(at 5.4102 0.29845 90)
			(unlocked yes)
			(layer "F.SilkS")
			(effects
				(font
					(size 1.905 1.4224)
					(thickness 0.1524)
				)
				(justify left)
			)
		)
		(fp_text user "+"
			(at -5.202682 -0.27305 270)
			(unlocked yes)
			(layer "F.SilkS")
			(effects
				(font
					(size 1.905 1.4224)
					(thickness 0.1524)
				)
				(justify left)
			)
		)
		(fp_text user "-"
			(at 5.4102 0.29845 90)
			(unlocked yes)
			(layer "F.Fab")
			(effects
				(font
					(size 1.905 1.4224)
					(thickness 0.1524)
				)
				(justify left)
			)
		)
		(fp_text user "+"
			(at -4.7752 -0.12065 270)
			(unlocked yes)
			(layer "F.Fab")
			(effects
				(font
					(size 1.905 1.4224)
					(thickness 0.1524)
				)
				(justify left)
			)
		)
		(pad "A" smd rect
			(at -1.999996 0)
			(size 1.7018 2.5146)
			(layers "F.Cu" "F.Mask" "F.Paste")
			(net "GND")
		)
		(pad "C" smd rect
			(at 1.999996 0)
			(size 1.7018 2.5146)
			(layers "F.Cu" "F.Mask" "F.Paste")
			(net "P12V_SSD6_R")
		)
	)
)
